(kicad_pcb
	(version 20260206)
	(generator "pcbnew")
	(generator_version "10.0")
	(general
		(thickness 1.6)
		(legacy_teardrops no)
	)
	(paper "A4")
	(title_block
		(title "04192023_DAF0TMB3IC0_F0TG_MB_C_brd_V02_OCP.brd")
		(comment 1 "Grand Teton / footprints 3917-3922 of 8354")
	)
	(layers
		(0 "F.Cu" signal "TOP")
		(4 "In1.Cu" signal "GND")
		(6 "In2.Cu" signal "IN1")
		(8 "In3.Cu" signal "GND1")
		(10 "In4.Cu" signal "IN2")
		(12 "In5.Cu" signal "GND2")
		(14 "In6.Cu" signal "IN3")
		(16 "In7.Cu" signal "GND3")
		(18 "In8.Cu" signal "VCC")
		(20 "In9.Cu" signal "VCC1")
		(22 "In10.Cu" signal "GND4")
		(24 "In11.Cu" signal "IN4")
		(26 "In12.Cu" signal "GND5")
		(28 "In13.Cu" signal "IN5")
		(30 "In14.Cu" signal "GND6")
		(32 "In15.Cu" signal "IN6")
		(34 "In16.Cu" signal "GND7")
		(2 "B.Cu" signal "BOTTOM")
		(9 "F.Adhes" user "F.Adhesive")
		(11 "B.Adhes" user "B.Adhesive")
		(13 "F.Paste" user "Package Geometry/Pastemask Top")
		(15 "B.Paste" user "Package Geometry/Pastemask Bottom")
		(5 "F.SilkS" user "Ref Des/Silkscreen Top")
		(7 "B.SilkS" user "Ref Des/Silkscreen Bottom")
		(1 "F.Mask" user "Board Geometry/Soldermask Top")
		(3 "B.Mask" user "Board Geometry/Soldermask Bottom")
		(17 "Dwgs.User" user "User.Drawings")
		(19 "Cmts.User" user "User.Comments")
		(21 "Eco1.User" user "User.Eco1")
		(23 "Eco2.User" user "User.Eco2")
		(25 "Edge.Cuts" user "Board Geometry/Outline")
		(27 "Margin" user)
		(31 "F.CrtYd" user "Package Geometry/Place Bound Top")
		(29 "B.CrtYd" user "Package Geometry/Place Bound Bottom")
		(35 "F.Fab" user "Ref Des/Assembly Top")
		(33 "B.Fab" user "Ref Des/Assembly Bottom")
	)
	(footprint ""
		(layer "F.Cu")
		(at 447.919602 -428.61611 90)
		(property "Reference" "PC6605"
			(at 0 0 90)
			(layer "F.SilkS")
			(hide yes)
			(effects
				(font
					(size 1.27 1.27)
				)
			)
		)
		(property "Value" ""
			(at 0 0 90)
			(layer "F.Fab")
			(effects
				(font
					(size 1.27 1.27)
				)
			)
		)
		(duplicate_pad_numbers_are_jumpers no)
		(fp_line
			(start 0.7874 -0.4064)
			(end 0.7874 0.4064)
			(stroke
				(width 0.1524)
				(type default)
			)
			(layer "F.SilkS")
		)
		(fp_line
			(start -0.7874 -0.4064)
			(end 0.7874 -0.4064)
			(stroke
				(width 0.1524)
				(type default)
			)
			(layer "F.SilkS")
		)
		(fp_line
			(start 0.7874 0.4064)
			(end -0.7874 0.4064)
			(stroke
				(width 0.1524)
				(type default)
			)
			(layer "F.SilkS")
		)
		(fp_line
			(start -0.7874 0.4064)
			(end -0.7874 -0.4064)
			(stroke
				(width 0.1524)
				(type default)
			)
			(layer "F.SilkS")
		)
		(fp_line
			(start -0.12065 -0.305054)
			(end -0.12065 -0.2794)
			(stroke
				(width 0.1)
				(type default)
			)
			(layer "F.Fab")
		)
		(fp_line
			(start -0.67945 -0.305054)
			(end -0.12065 -0.305054)
			(stroke
				(width 0.1)
				(type default)
			)
			(layer "F.Fab")
		)
		(fp_line
			(start 0.67945 -0.3048)
			(end 0.67945 0.3048)
			(stroke
				(width 0.1)
				(type default)
			)
			(layer "F.Fab")
		)
		(fp_line
			(start 0.12065 -0.3048)
			(end 0.67945 -0.3048)
			(stroke
				(width 0.1)
				(type default)
			)
			(layer "F.Fab")
		)
		(fp_line
			(start 0.12065 -0.2794)
			(end 0.12065 -0.3048)
			(stroke
				(width 0.1)
				(type default)
			)
			(layer "F.Fab")
		)
		(fp_line
			(start -0.12065 -0.2794)
			(end 0.12065 -0.2794)
			(stroke
				(width 0.1)
				(type default)
			)
			(layer "F.Fab")
		)
		(fp_line
			(start 0.120396 0.2794)
			(end -0.12065 0.2794)
			(stroke
				(width 0.1)
				(type default)
			)
			(layer "F.Fab")
		)
		(fp_line
			(start -0.12065 0.2794)
			(end -0.12065 0.3048)
			(stroke
				(width 0.1)
				(type default)
			)
			(layer "F.Fab")
		)
		(fp_line
			(start 0.67945 0.3048)
			(end 0.120396 0.3048)
			(stroke
				(width 0.1)
				(type default)
			)
			(layer "F.Fab")
		)
		(fp_line
			(start 0.120396 0.3048)
			(end 0.120396 0.2794)
			(stroke
				(width 0.1)
				(type default)
			)
			(layer "F.Fab")
		)
		(fp_line
			(start -0.12065 0.3048)
			(end -0.67945 0.3048)
			(stroke
				(width 0.1)
				(type default)
			)
			(layer "F.Fab")
		)
		(fp_line
			(start -0.67945 0.3048)
			(end -0.67945 -0.305054)
			(stroke
				(width 0.1)
				(type default)
			)
			(layer "F.Fab")
		)
		(pad "1" smd circle
			(at -0.40005 0 90)
			(size 0 0)
			(layers "F.Cu" "F.Mask" "F.Paste")
			(net "PV09_RETIMER_CPU0_VCCS")
		)
		(pad "2" smd circle
			(at 0.40005 0 90)
			(size 0 0)
			(layers "F.Cu" "F.Mask" "F.Paste")
			(net "GND")
		)
	)
	(footprint ""
		(layer "F.Cu")
		(at 39.27856 -108.72216 90)
		(property "Reference" "Q7000"
			(at -1.78816 2.61493 90)
			(unlocked yes)
			(layer "F.SilkS")
			(effects
				(font
					(size 0.7874 0.5842)
					(thickness 0.1524)
				)
				(justify left)
			)
		)
		(property "Value" ""
			(at 0 0 90)
			(layer "F.Fab")
			(effects
				(font
					(size 1.27 1.27)
				)
			)
		)
		(duplicate_pad_numbers_are_jumpers no)
		(fp_line
			(start 1.603248 -1.500124)
			(end 1.603248 1.500124)
			(stroke
				(width 0.1524)
				(type default)
			)
			(layer "F.SilkS")
		)
		(fp_line
			(start -1.603248 -1.500124)
			(end 1.603248 -1.500124)
			(stroke
				(width 0.1524)
				(type default)
			)
			(layer "F.SilkS")
		)
		(fp_line
			(start 1.603248 1.500124)
			(end -1.603248 1.500124)
			(stroke
				(width 0.1524)
				(type default)
			)
			(layer "F.SilkS")
		)
		(fp_line
			(start -1.603248 1.500124)
			(end -1.603248 -1.500124)
			(stroke
				(width 0.1524)
				(type default)
			)
			(layer "F.SilkS")
		)
		(fp_line
			(start 0.700024 -1.500124)
			(end -0.700024 -1.500124)
			(stroke
				(width 0.1)
				(type default)
			)
			(layer "F.Fab")
		)
		(fp_line
			(start -0.700024 -1.500124)
			(end -0.700024 -1.169924)
			(stroke
				(width 0.1)
				(type default)
			)
			(layer "F.Fab")
		)
		(fp_line
			(start -0.700024 -1.169924)
			(end -1.249934 -1.169924)
			(stroke
				(width 0.1)
				(type default)
			)
			(layer "F.Fab")
		)
		(fp_line
			(start -1.249934 -1.169924)
			(end -1.249934 -0.729996)
			(stroke
				(width 0.1)
				(type default)
			)
			(layer "F.Fab")
		)
		(fp_line
			(start -0.6985 -0.729996)
			(end -0.6985 0.729996)
			(stroke
				(width 0.1)
				(type default)
			)
			(layer "F.Fab")
		)
		(fp_line
			(start -1.249934 -0.729996)
			(end -0.6985 -0.729996)
			(stroke
				(width 0.1)
				(type default)
			)
			(layer "F.Fab")
		)
		(fp_line
			(start 1.249934 -0.219964)
			(end 0.700024 -0.219964)
			(stroke
				(width 0.1)
				(type default)
			)
			(layer "F.Fab")
		)
		(fp_line
			(start 0.700024 -0.219964)
			(end 0.700024 -1.500124)
			(stroke
				(width 0.1)
				(type default)
			)
			(layer "F.Fab")
		)
		(fp_line
			(start 1.249934 0.219964)
			(end 1.249934 -0.219964)
			(stroke
				(width 0.1)
				(type default)
			)
			(layer "F.Fab")
		)
		(fp_line
			(start 0.700024 0.219964)
			(end 1.249934 0.219964)
			(stroke
				(width 0.1)
				(type default)
			)
			(layer "F.Fab")
		)
		(fp_line
			(start -0.6985 0.729996)
			(end -1.249934 0.729996)
			(stroke
				(width 0.1)
				(type default)
			)
			(layer "F.Fab")
		)
		(fp_line
			(start -1.249934 0.729996)
			(end -1.249934 1.169924)
			(stroke
				(width 0.1)
				(type default)
			)
			(layer "F.Fab")
		)
		(fp_line
			(start -0.700024 1.169924)
			(end -0.700024 1.500124)
			(stroke
				(width 0.1)
				(type default)
			)
			(layer "F.Fab")
		)
		(fp_line
			(start -1.249934 1.169924)
			(end -0.700024 1.169924)
			(stroke
				(width 0.1)
				(type default)
			)
			(layer "F.Fab")
		)
		(fp_line
			(start 0.700024 1.500124)
			(end 0.700024 0.219964)
			(stroke
				(width 0.1)
				(type default)
			)
			(layer "F.Fab")
		)
		(fp_line
			(start -0.700024 1.500124)
			(end 0.700024 1.500124)
			(stroke
				(width 0.1)
				(type default)
			)
			(layer "F.Fab")
		)
		(fp_rect
			(start -0.700024 1.500124)
			(end 0.700024 -1.500124)
			(stroke
				(width 0)
				(type default)
			)
			(fill no)
			(layer "F.Fab")
		)
		(pad "D" smd rect
			(at 0.999998 0)
			(size 0.8128 0.9144)
			(layers "F.Cu" "F.Mask" "F.Paste")
			(net "P12V_AUX_DSC_G2")
		)
		(pad "G" smd rect
			(at -0.999998 -0.94996)
			(size 0.8128 0.9144)
			(layers "F.Cu" "F.Mask" "F.Paste")
			(net "P12V_AUX_DSC_G1")
		)
		(pad "S" smd rect
			(at -0.999998 0.94996)
			(size 0.8128 0.9144)
			(layers "F.Cu" "F.Mask" "F.Paste")
			(net "P12V_AUX_DSC_S1")
		)
	)
	(footprint ""
		(layer "F.Cu")
		(at 307.404516 -439.276744 90)
		(property "Reference" "C17"
			(at 0 0 90)
			(layer "F.SilkS")
			(hide yes)
			(effects
				(font
					(size 1.27 1.27)
				)
			)
		)
		(property "Value" ""
			(at 0 0 90)
			(layer "F.Fab")
			(effects
				(font
					(size 1.27 1.27)
				)
			)
		)
		(duplicate_pad_numbers_are_jumpers no)
		(fp_line
			(start 0.7874 -0.4064)
			(end 0.7874 0.4064)
			(stroke
				(width 0.1524)
				(type default)
			)
			(layer "F.SilkS")
		)
		(fp_line
			(start -0.7874 -0.4064)
			(end 0.7874 -0.4064)
			(stroke
				(width 0.1524)
				(type default)
			)
			(layer "F.SilkS")
		)
		(fp_line
			(start 0.7874 0.4064)
			(end -0.7874 0.4064)
			(stroke
				(width 0.1524)
				(type default)
			)
			(layer "F.SilkS")
		)
		(fp_line
			(start -0.7874 0.4064)
			(end -0.7874 -0.4064)
			(stroke
				(width 0.1524)
				(type default)
			)
			(layer "F.SilkS")
		)
		(fp_line
			(start -0.12065 -0.305054)
			(end -0.12065 -0.2794)
			(stroke
				(width 0.1)
				(type default)
			)
			(layer "F.Fab")
		)
		(fp_line
			(start -0.67945 -0.305054)
			(end -0.12065 -0.305054)
			(stroke
				(width 0.1)
				(type default)
			)
			(layer "F.Fab")
		)
		(fp_line
			(start 0.67945 -0.3048)
			(end 0.67945 0.3048)
			(stroke
				(width 0.1)
				(type default)
			)
			(layer "F.Fab")
		)
		(fp_line
			(start 0.12065 -0.3048)
			(end 0.67945 -0.3048)
			(stroke
				(width 0.1)
				(type default)
			)
			(layer "F.Fab")
		)
		(fp_line
			(start 0.12065 -0.2794)
			(end 0.12065 -0.3048)
			(stroke
				(width 0.1)
				(type default)
			)
			(layer "F.Fab")
		)
		(fp_line
			(start -0.12065 -0.2794)
			(end 0.12065 -0.2794)
			(stroke
				(width 0.1)
				(type default)
			)
			(layer "F.Fab")
		)
		(fp_line
			(start 0.120396 0.2794)
			(end -0.12065 0.2794)
			(stroke
				(width 0.1)
				(type default)
			)
			(layer "F.Fab")
		)
		(fp_line
			(start -0.12065 0.2794)
			(end -0.12065 0.3048)
			(stroke
				(width 0.1)
				(type default)
			)
			(layer "F.Fab")
		)
		(fp_line
			(start 0.67945 0.3048)
			(end 0.120396 0.3048)
			(stroke
				(width 0.1)
				(type default)
			)
			(layer "F.Fab")
		)
		(fp_line
			(start 0.120396 0.3048)
			(end 0.120396 0.2794)
			(stroke
				(width 0.1)
				(type default)
			)
			(layer "F.Fab")
		)
		(fp_line
			(start -0.12065 0.3048)
			(end -0.67945 0.3048)
			(stroke
				(width 0.1)
				(type default)
			)
			(layer "F.Fab")
		)
		(fp_line
			(start -0.67945 0.3048)
			(end -0.67945 -0.305054)
			(stroke
				(width 0.1)
				(type default)
			)
			(layer "F.Fab")
		)
		(pad "1" smd circle
			(at -0.40005 0 90)
			(size 0 0)
			(layers "F.Cu" "F.Mask" "F.Paste")
			(net "GPU_3V3IO_RSVD5_FFU_ISO")
		)
		(pad "2" smd circle
			(at 0.40005 0 90)
			(size 0 0)
			(layers "F.Cu" "F.Mask" "F.Paste")
			(net "GND")
		)
	)
	(footprint ""
		(layer "F.Cu")
		(at 275.14169 -99.371404 180)
		(property "Reference" "R1645"
			(at 0 0 180)
			(layer "F.SilkS")
			(hide yes)
			(effects
				(font
					(size 1.27 1.27)
				)
			)
		)
		(property "Value" ""
			(at 0 0 180)
			(layer "F.Fab")
			(effects
				(font
					(size 1.27 1.27)
				)
			)
		)
		(duplicate_pad_numbers_are_jumpers no)
		(fp_line
			(start 0.7874 0.4064)
			(end -0.7874 0.4064)
			(stroke
				(width 0.1524)
				(type default)
			)
			(layer "F.SilkS")
		)
		(fp_line
			(start 0.7874 -0.4064)
			(end 0.7874 0.4064)
			(stroke
				(width 0.1524)
				(type default)
			)
			(layer "F.SilkS")
		)
		(fp_line
			(start -0.7874 0.4064)
			(end -0.7874 -0.4064)
			(stroke
				(width 0.1524)
				(type default)
			)
			(layer "F.SilkS")
		)
		(fp_line
			(start -0.7874 -0.4064)
			(end 0.7874 -0.4064)
			(stroke
				(width 0.1524)
				(type default)
			)
			(layer "F.SilkS")
		)
		(fp_line
			(start 0.67945 0.3048)
			(end 0.120396 0.3048)
			(stroke
				(width 0.1)
				(type default)
			)
			(layer "F.Fab")
		)
		(fp_line
			(start 0.67945 -0.3048)
			(end 0.67945 0.3048)
			(stroke
				(width 0.1)
				(type default)
			)
			(layer "F.Fab")
		)
		(fp_line
			(start 0.12065 -0.2794)
			(end 0.12065 -0.3048)
			(stroke
				(width 0.1)
				(type default)
			)
			(layer "F.Fab")
		)
		(fp_line
			(start 0.12065 -0.3048)
			(end 0.67945 -0.3048)
			(stroke
				(width 0.1)
				(type default)
			)
			(layer "F.Fab")
		)
		(fp_line
			(start 0.120396 0.3048)
			(end 0.120396 0.2794)
			(stroke
				(width 0.1)
				(type default)
			)
			(layer "F.Fab")
		)
		(fp_line
			(start 0.120396 0.2794)
			(end -0.12065 0.2794)
			(stroke
				(width 0.1)
				(type default)
			)
			(layer "F.Fab")
		)
		(fp_line
			(start -0.12065 0.3048)
			(end -0.67945 0.3048)
			(stroke
				(width 0.1)
				(type default)
			)
			(layer "F.Fab")
		)
		(fp_line
			(start -0.12065 0.2794)
			(end -0.12065 0.3048)
			(stroke
				(width 0.1)
				(type default)
			)
			(layer "F.Fab")
		)
		(fp_line
			(start -0.12065 -0.2794)
			(end 0.12065 -0.2794)
			(stroke
				(width 0.1)
				(type default)
			)
			(layer "F.Fab")
		)
		(fp_line
			(start -0.12065 -0.305054)
			(end -0.12065 -0.2794)
			(stroke
				(width 0.1)
				(type default)
			)
			(layer "F.Fab")
		)
		(fp_line
			(start -0.67945 0.3048)
			(end -0.67945 -0.305054)
			(stroke
				(width 0.1)
				(type default)
			)
			(layer "F.Fab")
		)
		(fp_line
			(start -0.67945 -0.305054)
			(end -0.12065 -0.305054)
			(stroke
				(width 0.1)
				(type default)
			)
			(layer "F.Fab")
		)
		(pad "1" smd circle
			(at -0.40005 0 180)
			(size 0 0)
			(layers "F.Cu" "F.Mask" "F.Paste")
			(net "JTAG_P1_R_DBREQ_N")
		)
		(pad "2" smd circle
			(at 0.40005 0 180)
			(size 0 0)
			(layers "F.Cu" "F.Mask" "F.Paste")
			(net "JTAG_CPU1_DBREQ_N")
		)
	)
	(footprint ""
		(layer "F.Cu")
		(at 393.363958 -322.627752 180)
		(property "Reference" "R389"
			(at 0 0 180)
			(layer "F.SilkS")
			(hide yes)
			(effects
				(font
					(size 1.27 1.27)
				)
			)
		)
		(property "Value" ""
			(at 0 0 180)
			(layer "F.Fab")
			(effects
				(font
					(size 1.27 1.27)
				)
			)
		)
		(duplicate_pad_numbers_are_jumpers no)
		(fp_line
			(start 0.7874 0.4064)
			(end -0.7874 0.4064)
			(stroke
				(width 0.1524)
				(type default)
			)
			(layer "F.SilkS")
		)
		(fp_line
			(start 0.7874 -0.4064)
			(end 0.7874 0.4064)
			(stroke
				(width 0.1524)
				(type default)
			)
			(layer "F.SilkS")
		)
		(fp_line
			(start -0.7874 0.4064)
			(end -0.7874 -0.4064)
			(stroke
				(width 0.1524)
				(type default)
			)
			(layer "F.SilkS")
		)
		(fp_line
			(start -0.7874 -0.4064)
			(end 0.7874 -0.4064)
			(stroke
				(width 0.1524)
				(type default)
			)
			(layer "F.SilkS")
		)
		(fp_line
			(start 0.67945 0.3048)
			(end 0.120396 0.3048)
			(stroke
				(width 0.1)
				(type default)
			)
			(layer "F.Fab")
		)
		(fp_line
			(start 0.67945 -0.3048)
			(end 0.67945 0.3048)
			(stroke
				(width 0.1)
				(type default)
			)
			(layer "F.Fab")
		)
		(fp_line
			(start 0.12065 -0.2794)
			(end 0.12065 -0.3048)
			(stroke
				(width 0.1)
				(type default)
			)
			(layer "F.Fab")
		)
		(fp_line
			(start 0.12065 -0.3048)
			(end 0.67945 -0.3048)
			(stroke
				(width 0.1)
				(type default)
			)
			(layer "F.Fab")
		)
		(fp_line
			(start 0.120396 0.3048)
			(end 0.120396 0.2794)
			(stroke
				(width 0.1)
				(type default)
			)
			(layer "F.Fab")
		)
		(fp_line
			(start 0.120396 0.2794)
			(end -0.12065 0.2794)
			(stroke
				(width 0.1)
				(type default)
			)
			(layer "F.Fab")
		)
		(fp_line
			(start -0.12065 0.3048)
			(end -0.67945 0.3048)
			(stroke
				(width 0.1)
				(type default)
			)
			(layer "F.Fab")
		)
		(fp_line
			(start -0.12065 0.2794)
			(end -0.12065 0.3048)
			(stroke
				(width 0.1)
				(type default)
			)
			(layer "F.Fab")
		)
		(fp_line
			(start -0.12065 -0.2794)
			(end 0.12065 -0.2794)
			(stroke
				(width 0.1)
				(type default)
			)
			(layer "F.Fab")
		)
		(fp_line
			(start -0.12065 -0.305054)
			(end -0.12065 -0.2794)
			(stroke
				(width 0.1)
				(type default)
			)
			(layer "F.Fab")
		)
		(fp_line
			(start -0.67945 0.3048)
			(end -0.67945 -0.305054)
			(stroke
				(width 0.1)
				(type default)
			)
			(layer "F.Fab")
		)
		(fp_line
			(start -0.67945 -0.305054)
			(end -0.12065 -0.305054)
			(stroke
				(width 0.1)
				(type default)
			)
			(layer "F.Fab")
		)
		(pad "1" smd circle
			(at -0.40005 0 180)
			(size 0 0)
			(layers "F.Cu" "F.Mask" "F.Paste")
			(net "P3V3_AUX")
		)
		(pad "2" smd circle
			(at 0.40005 0 180)
			(size 0 0)
			(layers "F.Cu" "F.Mask" "F.Paste")
			(net "CPU0_SP5R4")
		)
	)
	(footprint ""
		(layer "F.Cu")
		(at 332.763876 -70.098412 90)
		(property "Reference" "D78"
			(at -3.934714 -0.691642 90)
			(unlocked yes)
			(layer "F.SilkS")
			(effects
				(font
					(size 0.7874 0.5842)
					(thickness 0.1524)
				)
				(justify left)
			)
		)
		(property "Value" ""
			(at 0 0 90)
			(layer "F.Fab")
			(effects
				(font
					(size 1.27 1.27)
				)
			)
		)
		(duplicate_pad_numbers_are_jumpers no)
		(fp_line
			(start 1.16078 -0.4826)
			(end 1.16078 0.4826)
			(stroke
				(width 0.1524)
				(type default)
			)
			(layer "F.SilkS")
		)
		(fp_line
			(start 1.03378 -0.4826)
			(end 1.03378 0.4826)
			(stroke
				(width 0.1524)
				(type default)
			)
			(layer "F.SilkS")
		)
		(fp_line
			(start 0.90678 -0.4826)
			(end 0.90678 0.4826)
			(stroke
				(width 0.1524)
				(type default)
			)
			(layer "F.SilkS")
		)
		(fp_line
			(start -0.64008 -0.4826)
			(end 1.16078 -0.4826)
			(stroke
				(width 0.1524)
				(type default)
			)
			(layer "F.SilkS")
		)
		(fp_line
			(start -0.79248 -0.4826)
			(end 1.03378 -0.4826)
			(stroke
				(width 0.1524)
				(type default)
			)
			(layer "F.SilkS")
		)
		(fp_line
			(start -0.89408 -0.4826)
			(end 0.90678 -0.4826)
			(stroke
				(width 0.1524)
				(type default)
			)
			(layer "F.SilkS")
		)
		(fp_line
			(start 1.16078 0.4826)
			(end -0.64008 0.4826)
			(stroke
				(width 0.1524)
				(type default)
			)
			(layer "F.SilkS")
		)
		(fp_line
			(start 1.03378 0.4826)
			(end -0.79248 0.4826)
			(stroke
				(width 0.1524)
				(type default)
			)
			(layer "F.SilkS")
		)
		(fp_line
			(start 0.90678 0.4826)
			(end -0.90678 0.4826)
			(stroke
				(width 0.1524)
				(type default)
			)
			(layer "F.SilkS")
		)
		(fp_line
			(start -0.90678 0.4826)
			(end -0.90678 -0.4699)
			(stroke
				(width 0.1524)
				(type default)
			)
			(layer "F.SilkS")
		)
		(fp_line
			(start 0.499872 -0.249936)
			(end 0.499872 0.249936)
			(stroke
				(width 0.1)
				(type default)
			)
			(layer "F.Fab")
		)
		(fp_line
			(start -0.499872 -0.249936)
			(end 0.499872 -0.249936)
			(stroke
				(width 0.1)
				(type default)
			)
			(layer "F.Fab")
		)
		(fp_line
			(start 0.499872 0.249936)
			(end -0.499872 0.249936)
			(stroke
				(width 0.1)
				(type default)
			)
			(layer "F.Fab")
		)
		(fp_line
			(start -0.499872 0.249936)
			(end -0.499872 -0.249936)
			(stroke
				(width 0.1)
				(type default)
			)
			(layer "F.Fab")
		)
		(pad "A" smd rect
			(at -0.47498 0 90)
			(size 0.6096 0.7112)
			(layers "F.Cu" "F.Mask" "F.Paste")
			(net "LED_PWRGD_PVDD11_S3_P0_R")
		)
		(pad "C" smd rect
			(at 0.47498 0 90)
			(size 0.6096 0.7112)
			(layers "F.Cu" "F.Mask" "F.Paste")
			(net "LED_PWRGD_PVDD11_S3_P0_D")
		)
	)
)
